(kicad_pcb
	(version 20221018)
	(generator pcbnew)
	(general
    (thickness 1.586)
  )
	(paper "A4")
	(title_block
    (date "2024-03-26")
    (rev "1.1.3")
		(comment 9 "footprints 115-118 of 146")
	)
	(layers
    (0 "F.Cu" signal)
    (1 "In1.Cu" power)
    (2 "In2.Cu" power)
    (31 "B.Cu" signal)
    (32 "B.Adhes" user "B.Adhesive")
    (33 "F.Adhes" user "F.Adhesive")
    (34 "B.Paste" user)
    (35 "F.Paste" user)
    (36 "B.SilkS" user "B.Silkscreen")
    (37 "F.SilkS" user "F.Silkscreen")
    (38 "B.Mask" user)
    (39 "F.Mask" user)
    (40 "Dwgs.User" user "User.Drawings")
    (41 "Cmts.User" user "User.Comments")
    (42 "Eco1.User" user "User.Eco1")
    (43 "Eco2.User" user "User.Eco2")
    (44 "Edge.Cuts" user)
    (45 "Margin" user)
    (46 "B.CrtYd" user "B.Courtyard")
    (47 "F.CrtYd" user "F.Courtyard")
    (48 "B.Fab" user)
    (49 "F.Fab" user)
  )
	(footprint "scalenode-cm4-baseboard-footprints:R_1206_3216Metric" (layer "B.Cu")
    (at 151.6 89 -90)
    (property "Author" "Antmicro")
    (property "Current" "2A")
    (property "License" "Apache-2.0")
    (property "MPN" "MCMR12X000_PTL")
    (property "Manufacturer" "Multicomp Pro")
    (property "Sheetfile" "expansion-connectors.kicad_sch")
    (property "Sheetname" "Expansion connectors")
    (property "Tolerance" "~")
    (property "Val" "0R")
    (property "ki_description" "0R resistor in 1206 package with unspecified tolerance")
    (attr smd)
    (fp_text reference "R62" (at -0.825 1.325 90) (layer "B.SilkS")
        (effects (font (size 0.7 0.7) (thickness 0.15)) (justify left bottom mirror))
    )
    (fp_text value "R_0R_1206" (at 0 -2 90) (layer "B.Fab")
        (effects (font (size 0.7 0.7) (thickness 0.15)) (justify left bottom mirror))
    )
    (fp_text user "License: Apache-2.0" (at -2.401 -6.3 90) (layer "B.Fab") hide
        (effects (font (size 0.7 0.7) (thickness 0.15)) (justify left bottom mirror))
    )
    (fp_text user "Author: Antmicro" (at -2.401 -4.899 90) (layer "B.Fab") hide
        (effects (font (size 0.7 0.7) (thickness 0.15)) (justify left bottom mirror))
    )
    (fp_text user "${REFERENCE}" (at -2.401 -3.5 90) (layer "B.Fab") hide
        (effects (font (size 0.7 0.7) (thickness 0.15)) (justify left bottom mirror))
    )
    (fp_line (start 0 -0.9) (end -0.5 -0.9)
      (stroke (width 0.15) (type solid)) (layer "B.SilkS"))
    (fp_line (start 0 -0.9) (end 0.498 -0.9)
      (stroke (width 0.15) (type solid)) (layer "B.SilkS"))
    (fp_line (start 0 0.902) (end -0.5 0.902)
      (stroke (width 0.15) (type solid)) (layer "B.SilkS"))
    (fp_line (start 0 0.902) (end 0.498 0.902)
      (stroke (width 0.15) (type solid)) (layer "B.SilkS"))
    (fp_rect (start -2.25 1.05) (end 2.25 -1.05)
      (stroke (width 0.05) (type solid)) (fill none) (layer "B.CrtYd"))
    (fp_line (start -1.601 -0.8) (end 1.6 -0.8)
      (stroke (width 0.15) (type solid)) (layer "B.Fab"))
    (fp_line (start -1.601 0.802) (end -1.601 -0.8)
      (stroke (width 0.15) (type solid)) (layer "B.Fab"))
    (fp_line (start -1.601 0.802) (end 1.6 0.802)
      (stroke (width 0.15) (type solid)) (layer "B.Fab"))
    (fp_line (start 1.6 0.802) (end 1.6 -0.8)
      (stroke (width 0.15) (type solid)) (layer "B.Fab"))
    (pad "1" smd roundrect (at -1.5 0 270) (size 1.2 1.8) (layers "B.Cu" "B.Paste" "B.Mask") (roundrect_rratio 0.15)
      (net 253 "3V3_OUT") (pintype "passive"))
    (pad "2" smd roundrect (at 1.499 0 270) (size 1.2 1.8) (layers "B.Cu" "B.Paste" "B.Mask") (roundrect_rratio 0.15)
      (net 170 "3V3_SSD") (pintype "passive"))
  )
	(footprint "scalenode-cm4-baseboard-footprints:R_1206_3216Metric" (layer "B.Cu")
    (at 151.6 85.4 90)
    (property "Author" "Antmicro")
    (property "Current" "2A")
    (property "DNP" "DNP")
    (property "License" "Apache-2.0")
    (property "MPN" "MCMR12X000_PTL")
    (property "Manufacturer" "Multicomp Pro")
    (property "Sheetfile" "expansion-connectors.kicad_sch")
    (property "Sheetname" "Expansion connectors")
    (property "Tolerance" "~")
    (property "Val" "0R")
    (property "dnp" "")
    (property "exclude_from_bom" "")
    (property "ki_description" "0R resistor in 1206 package with unspecified tolerance")
    (attr exclude_from_pos_files exclude_from_bom)
    (fp_text reference "R63" (at 1.225 -1.35 270) (layer "B.SilkS")
        (effects (font (size 0.7 0.7) (thickness 0.15)) (justify left bottom mirror))
    )
    (fp_text value "R_0R_1206" (at 0 -2 270) (layer "B.Fab")
        (effects (font (size 0.7 0.7) (thickness 0.15)) (justify left bottom mirror))
    )
    (fp_text user "Author: Antmicro" (at -2.401 -4.899 270) (layer "B.Fab") hide
        (effects (font (size 0.7 0.7) (thickness 0.15)) (justify left bottom mirror))
    )
    (fp_text user "${REFERENCE}" (at -2.401 -3.5 270) (layer "B.Fab") hide
        (effects (font (size 0.7 0.7) (thickness 0.15)) (justify left bottom mirror))
    )
    (fp_text user "License: Apache-2.0" (at -2.401 -6.3 270) (layer "B.Fab") hide
        (effects (font (size 0.7 0.7) (thickness 0.15)) (justify left bottom mirror))
    )
    (fp_line (start 0 -0.9) (end -0.5 -0.9)
      (stroke (width 0.15) (type solid)) (layer "B.SilkS"))
    (fp_line (start 0 -0.9) (end 0.498 -0.9)
      (stroke (width 0.15) (type solid)) (layer "B.SilkS"))
    (fp_line (start 0 0.902) (end -0.5 0.902)
      (stroke (width 0.15) (type solid)) (layer "B.SilkS"))
    (fp_line (start 0 0.902) (end 0.498 0.902)
      (stroke (width 0.15) (type solid)) (layer "B.SilkS"))
    (fp_rect (start -2.25 1.05) (end 2.25 -1.05)
      (stroke (width 0.05) (type solid)) (fill none) (layer "B.CrtYd"))
    (fp_line (start -1.601 -0.8) (end 1.6 -0.8)
      (stroke (width 0.15) (type solid)) (layer "B.Fab"))
    (fp_line (start -1.601 0.802) (end -1.601 -0.8)
      (stroke (width 0.15) (type solid)) (layer "B.Fab"))
    (fp_line (start -1.601 0.802) (end 1.6 0.802)
      (stroke (width 0.15) (type solid)) (layer "B.Fab"))
    (fp_line (start 1.6 0.802) (end 1.6 -0.8)
      (stroke (width 0.15) (type solid)) (layer "B.Fab"))
    (pad "1" smd roundrect (at -1.5 0 90) (size 1.2 1.8) (layers "B.Cu" "B.Paste" "B.Mask") (roundrect_rratio 0.15)
      (net 253 "3V3_OUT") (pintype "passive"))
    (pad "2" smd roundrect (at 1.499 0 90) (size 1.2 1.8) (layers "B.Cu" "B.Paste" "B.Mask") (roundrect_rratio 0.15)
      (net 232 "3V3_RPi") (pintype "passive"))
  )
	(footprint "scalenode-cm4-baseboard-footprints:TP_SMD_1mm" (layer "B.Cu")
    (at 134 83.75 180)
    (property "Author" "Antmicro")
    (property "License" "Apache-2.0")
    (property "MPN" "")
    (property "Manufacturer" "")
    (property "Sheetfile" "supply.kicad_sch")
    (property "Sheetname" "Supply")
    (property "ki_description" "Test Point 1mm")
    (attr exclude_from_pos_files)
    (fp_text reference "TP2" (at -1.275 0.65) (layer "B.SilkS")
        (effects (font (size 0.7 0.7) (thickness 0.15)) (justify left bottom mirror))
    )
    (fp_text value "TP_1mm_SMD" (at 0 -1.4) (layer "B.Fab")
        (effects (font (size 0.7 0.7) (thickness 0.15)) (justify left bottom mirror))
    )
    (fp_text user "License: Apache-2.0" (at -0.5 -5.2) (layer "B.Fab") hide
        (effects (font (size 0.7 0.7) (thickness 0.15)) (justify left bottom mirror))
    )
    (fp_text user "${REFERENCE}" (at -0.5 -2.8) (layer "B.Fab") hide
        (effects (font (size 0.7 0.7) (thickness 0.15)) (justify left bottom mirror))
    )
    (fp_text user "Author: Antmicro" (at -0.5 -4) (layer "B.Fab") hide
        (effects (font (size 0.7 0.7) (thickness 0.15)) (justify left bottom mirror))
    )
    (pad "1" smd circle (at 0 0 180) (size 1 1) (layers "B.Cu" "B.Mask")
      (net 270 "Net-(U2-EN)") (pinfunction "1") (pintype "passive"))
  )
	(footprint "scalenode-cm4-baseboard-footprints:SOIC-8-1EP_3.9x4.9x1.75mm_P1.27mm" (layer "B.Cu")
    (at 99.05 91.506)
    (tags "Integrated Circuit")
    (property "Author" "Antmicro")
    (property "License" "Apache-2.0")
    (property "MPN" "TPS2378DDA")
    (property "Manufacturer" "Texas Instruments")
    (property "Sheetfile" "poe.kicad_sch")
    (property "Sheetname" "PoE")
    (property "ki_description" "IEEE 802.3at PoE High-Power PD Interface with AUX Control")
    (attr smd)
    (fp_text reference "U8" (at 0.95 3.744 180) (layer "B.SilkS")
        (effects (font (size 0.7 0.7) (thickness 0.15)) (justify left bottom mirror))
    )
    (fp_text value "TPS2378DDA" (at 0 -3.65 180) (layer "B.Fab")
        (effects (font (size 0.7 0.7) (thickness 0.15)) (justify left bottom mirror))
    )
    (fp_text user "${REFERENCE}" (at -3.476 -7.099 180) (layer "B.Fab") hide
        (effects (font (size 0.7 0.7) (thickness 0.15)) (justify left bottom mirror))
    )
    (fp_text user "License: Apache-2.0" (at -3.476 -5.099 180) (layer "B.Fab") hide
        (effects (font (size 0.7 0.7) (thickness 0.15)) (justify left bottom mirror))
    )
    (fp_text user "Author: Antmicro" (at -3.476 -6.099 180) (layer "B.Fab") hide
        (effects (font (size 0.7 0.7) (thickness 0.15)) (justify left bottom mirror))
    )
    (fp_line (start 1.95 -2.55) (end -1.95 -2.55)
      (stroke (width 0.15) (type solid)) (layer "B.SilkS"))
    (fp_line (start 1.95 2.55) (end -1.95 2.55)
      (stroke (width 0.15) (type solid)) (layer "B.SilkS"))
    (fp_circle (center -2.5 2.45) (end -2.45 2.4)
      (stroke (width 0.15) (type solid)) (fill solid) (layer "B.SilkS"))
    (fp_rect (start -3.55 2.7) (end 3.55 -2.7)
      (stroke (width 0.05) (type solid)) (fill none) (layer "B.CrtYd"))
    (fp_line (start -1.95 -2.45) (end -1.95 1.18)
      (stroke (width 0.15) (type solid)) (layer "B.Fab"))
    (fp_line (start -1.95 1.18) (end -0.683 2.452)
      (stroke (width 0.15) (type solid)) (layer "B.Fab"))
    (fp_line (start -0.683 2.452) (end 1.949 2.452)
      (stroke (width 0.15) (type solid)) (layer "B.Fab"))
    (fp_line (start 1.949 -2.45) (end -1.95 -2.45)
      (stroke (width 0.15) (type solid)) (layer "B.Fab"))
    (fp_line (start 1.949 2.452) (end 1.949 -2.45)
      (stroke (width 0.15) (type solid)) (layer "B.Fab"))
    (pad "1" smd roundrect (at -2.714 1.905 270) (size 0.65 1.525) (layers "B.Cu" "B.Paste" "B.Mask") (roundrect_rratio 0.25)
      (net 6 "/PoE/VDD_POE_IN") (pinfunction "VDD") (pintype "power_in"))
    (pad "2" smd roundrect (at -2.714 0.635 270) (size 0.65 1.525) (layers "B.Cu" "B.Paste" "B.Mask") (roundrect_rratio 0.25)
      (net 256 "Net-(U8-DEN)") (pinfunction "DEN") (pintype "passive"))
    (pad "3" smd roundrect (at -2.714 -0.632 270) (size 0.65 1.525) (layers "B.Cu" "B.Paste" "B.Mask") (roundrect_rratio 0.25)
      (net 255 "Net-(U8-CLS)") (pinfunction "CLS") (pintype "passive"))
    (pad "4" smd roundrect (at -2.714 -1.902 270) (size 0.65 1.525) (layers "B.Cu" "B.Paste" "B.Mask") (roundrect_rratio 0.25)
      (net 5 "VSS") (pinfunction "VSS") (pintype "power_in"))
    (pad "5" smd roundrect (at 2.712 -1.902 270) (size 0.65 1.525) (layers "B.Cu" "B.Paste" "B.Mask") (roundrect_rratio 0.25)
      (net 4 "GNDD") (pinfunction "RTN") (pintype "passive"))
    (pad "6" smd roundrect (at 2.712 -0.632 270) (size 0.65 1.525) (layers "B.Cu" "B.Paste" "B.Mask") (roundrect_rratio 0.25)
      (net 34 "/PoE/POE_ACTIVE") (pinfunction "CDB") (pintype "passive"))
    (pad "7" smd roundrect (at 2.712 0.635 270) (size 0.65 1.525) (layers "B.Cu" "B.Paste" "B.Mask") (roundrect_rratio 0.25)
      (net 278 "unconnected-(U8-T2P-Pad7)") (pinfunction "T2P") (pintype "passive+no_connect"))
    (pad "8" smd roundrect (at 2.712 1.905 270) (size 0.65 1.525) (layers "B.Cu" "B.Paste" "B.Mask") (roundrect_rratio 0.25)
      (net 4 "GNDD") (pinfunction "APD") (pintype "passive"))
    (pad "9" smd roundrect (at 0 0) (size 2.29 3.1) (layers "B.Cu" "B.Paste" "B.Mask") (roundrect_rratio 0.05)
      (net 5 "VSS") (pinfunction "EP") (pintype "power_in"))
  )
)
